# T6G (Grand Teton) — schematic netlist excerpt (pin names and nets, part order shuffled) for the footprints in the layout excerpt that follows; sources: Cadence DE-HDL packaged netlist, KiCad conversion of 04192023_DAF0TMB3IC0_F0TG_MB_C_brd_V02_OCP.brd

PR3987  Q_RES  2K 0.1% CHIP  pkg 0402LF  page 264 : A = HSC_CS_4 ; B = AGND_HSC
PR229  Q_RES  49.9 1% CHIP  pkg 0402LF  page 224 : A = PVDD11_S3_P1 ; B = VSENSE_PVDD11_S3_P1_DP

(kicad_pcb
	(version 20260206)
	(generator "pcbnew")
	(generator_version "10.0")
	(general
		(thickness 1.6)
		(legacy_teardrops no)
	)
	(paper "A4")
	(title_block
		(title "04192023_DAF0TMB3IC0_F0TG_MB_C_brd_V02_OCP.brd")
		(comment 1 "Grand Teton / footprints 4334-4335 of 8354")
	)
	(layers
		(0 "F.Cu" signal "TOP")
		(4 "In1.Cu" signal "GND")
		(6 "In2.Cu" signal "IN1")
		(8 "In3.Cu" signal "GND1")
		(10 "In4.Cu" signal "IN2")
		(12 "In5.Cu" signal "GND2")
		(14 "In6.Cu" signal "IN3")
		(16 "In7.Cu" signal "GND3")
		(18 "In8.Cu" signal "VCC")
		(20 "In9.Cu" signal "VCC1")
		(22 "In10.Cu" signal "GND4")
		(24 "In11.Cu" signal "IN4")
		(26 "In12.Cu" signal "GND5")
		(28 "In13.Cu" signal "IN5")
		(30 "In14.Cu" signal "GND6")
		(32 "In15.Cu" signal "IN6")
		(34 "In16.Cu" signal "GND7")
		(2 "B.Cu" signal "BOTTOM")
		(9 "F.Adhes" user "F.Adhesive")
		(11 "B.Adhes" user "B.Adhesive")
		(13 "F.Paste" user "Package Geometry/Pastemask Top")
		(15 "B.Paste" user "Package Geometry/Pastemask Bottom")
		(5 "F.SilkS" user "Ref Des/Silkscreen Top")
		(7 "B.SilkS" user "Ref Des/Silkscreen Bottom")
		(1 "F.Mask" user "Board Geometry/Soldermask Top")
		(3 "B.Mask" user "Board Geometry/Soldermask Bottom")
		(17 "Dwgs.User" user "User.Drawings")
		(19 "Cmts.User" user "User.Comments")
		(21 "Eco1.User" user "User.Eco1")
		(23 "Eco2.User" user "User.Eco2")
		(25 "Edge.Cuts" user "Board Geometry/Outline")
		(27 "Margin" user)
		(31 "F.CrtYd" user "Package Geometry/Place Bound Top")
		(29 "B.CrtYd" user "Package Geometry/Place Bound Bottom")
		(35 "F.Fab" user "Ref Des/Assembly Top")
		(33 "B.Fab" user "Ref Des/Assembly Bottom")
	)
	(footprint ""
		(layer "F.Cu")
		(at 226.0981 -400.972782 180)
		(property "Reference" "PR3987"
			(at 0 0 180)
			(layer "F.SilkS")
			(hide yes)
			(effects
				(font
					(size 1.27 1.27)
				)
			)
		)
		(property "Value" ""
			(at 0 0 180)
			(layer "F.Fab")
			(effects
				(font
					(size 1.27 1.27)
				)
			)
		)
		(duplicate_pad_numbers_are_jumpers no)
		(fp_line
			(start 0.7874 0.4064)
			(end -0.7874 0.4064)
			(stroke
				(width 0.1524)
				(type default)
			)
			(layer "F.SilkS")
		)
		(fp_line
			(start 0.7874 -0.4064)
			(end 0.7874 0.4064)
			(stroke
				(width 0.1524)
				(type default)
			)
			(layer "F.SilkS")
		)
		(fp_line
			(start -0.7874 0.4064)
			(end -0.7874 -0.4064)
			(stroke
				(width 0.1524)
				(type default)
			)
			(layer "F.SilkS")
		)
		(fp_line
			(start -0.7874 -0.4064)
			(end 0.7874 -0.4064)
			(stroke
				(width 0.1524)
				(type default)
			)
			(layer "F.SilkS")
		)
		(fp_line
			(start 0.67945 0.3048)
			(end 0.120396 0.3048)
			(stroke
				(width 0.1)
				(type default)
			)
			(layer "F.Fab")
		)
		(fp_line
			(start 0.67945 -0.3048)
			(end 0.67945 0.3048)
			(stroke
				(width 0.1)
				(type default)
			)
			(layer "F.Fab")
		)
		(fp_line
			(start 0.12065 -0.2794)
			(end 0.12065 -0.3048)
			(stroke
				(width 0.1)
				(type default)
			)
			(layer "F.Fab")
		)
		(fp_line
			(start 0.12065 -0.3048)
			(end 0.67945 -0.3048)
			(stroke
				(width 0.1)
				(type default)
			)
			(layer "F.Fab")
		)
		(fp_line
			(start 0.120396 0.3048)
			(end 0.120396 0.2794)
			(stroke
				(width 0.1)
				(type default)
			)
			(layer "F.Fab")
		)
		(fp_line
			(start 0.120396 0.2794)
			(end -0.12065 0.2794)
			(stroke
				(width 0.1)
				(type default)
			)
			(layer "F.Fab")
		)
		(fp_line
			(start -0.12065 0.3048)
			(end -0.67945 0.3048)
			(stroke
				(width 0.1)
				(type default)
			)
			(layer "F.Fab")
		)
		(fp_line
			(start -0.12065 0.2794)
			(end -0.12065 0.3048)
			(stroke
				(width 0.1)
				(type default)
			)
			(layer "F.Fab")
		)
		(fp_line
			(start -0.12065 -0.2794)
			(end 0.12065 -0.2794)
			(stroke
				(width 0.1)
				(type default)
			)
			(layer "F.Fab")
		)
		(fp_line
			(start -0.12065 -0.305054)
			(end -0.12065 -0.2794)
			(stroke
				(width 0.1)
				(type default)
			)
			(layer "F.Fab")
		)
		(fp_line
			(start -0.67945 0.3048)
			(end -0.67945 -0.305054)
			(stroke
				(width 0.1)
				(type default)
			)
			(layer "F.Fab")
		)
		(fp_line
			(start -0.67945 -0.305054)
			(end -0.12065 -0.305054)
			(stroke
				(width 0.1)
				(type default)
			)
			(layer "F.Fab")
		)
		(pad "1" smd circle
			(at -0.40005 0 180)
			(size 0 0)
			(layers "F.Cu" "F.Mask" "F.Paste")
			(net "HSC_CS_4")
		)
		(pad "2" smd circle
			(at 0.40005 0 180)
			(size 0 0)
			(layers "F.Cu" "F.Mask" "F.Paste")
			(net "AGND_HSC")
		)
	)
	(footprint ""
		(layer "F.Cu")
		(at 170.8404 -333.375508 180)
		(property "Reference" "PR229"
			(at 0 0 180)
			(layer "F.SilkS")
			(hide yes)
			(effects
				(font
					(size 1.27 1.27)
				)
			)
		)
		(property "Value" ""
			(at 0 0 180)
			(layer "F.Fab")
			(effects
				(font
					(size 1.27 1.27)
				)
			)
		)
		(duplicate_pad_numbers_are_jumpers no)
		(fp_line
			(start 0.7874 0.4064)
			(end -0.7874 0.4064)
			(stroke
				(width 0.1524)
				(type default)
			)
			(layer "F.SilkS")
		)
		(fp_line
			(start 0.7874 -0.4064)
			(end 0.7874 0.4064)
			(stroke
				(width 0.1524)
				(type default)
			)
			(layer "F.SilkS")
		)
		(fp_line
			(start -0.7874 0.4064)
			(end -0.7874 -0.4064)
			(stroke
				(width 0.1524)
				(type default)
			)
			(layer "F.SilkS")
		)
		(fp_line
			(start -0.7874 -0.4064)
			(end 0.7874 -0.4064)
			(stroke
				(width 0.1524)
				(type default)
			)
			(layer "F.SilkS")
		)
		(fp_line
			(start 0.67945 0.3048)
			(end 0.120396 0.3048)
			(stroke
				(width 0.1)
				(type default)
			)
			(layer "F.Fab")
		)
		(fp_line
			(start 0.67945 -0.3048)
			(end 0.67945 0.3048)
			(stroke
				(width 0.1)
				(type default)
			)
			(layer "F.Fab")
		)
		(fp_line
			(start 0.12065 -0.2794)
			(end 0.12065 -0.3048)
			(stroke
				(width 0.1)
				(type default)
			)
			(layer "F.Fab")
		)
		(fp_line
			(start 0.12065 -0.3048)
			(end 0.67945 -0.3048)
			(stroke
				(width 0.1)
				(type default)
			)
			(layer "F.Fab")
		)
		(fp_line
			(start 0.120396 0.3048)
			(end 0.120396 0.2794)
			(stroke
				(width 0.1)
				(type default)
			)
			(layer "F.Fab")
		)
		(fp_line
			(start 0.120396 0.2794)
			(end -0.12065 0.2794)
			(stroke
				(width 0.1)
				(type default)
			)
			(layer "F.Fab")
		)
		(fp_line
			(start -0.12065 0.3048)
			(end -0.67945 0.3048)
			(stroke
				(width 0.1)
				(type default)
			)
			(layer "F.Fab")
		)
		(fp_line
			(start -0.12065 0.2794)
			(end -0.12065 0.3048)
			(stroke
				(width 0.1)
				(type default)
			)
			(layer "F.Fab")
		)
		(fp_line
			(start -0.12065 -0.2794)
			(end 0.12065 -0.2794)
			(stroke
				(width 0.1)
				(type default)
			)
			(layer "F.Fab")
		)
		(fp_line
			(start -0.12065 -0.305054)
			(end -0.12065 -0.2794)
			(stroke
				(width 0.1)
				(type default)
			)
			(layer "F.Fab")
		)
		(fp_line
			(start -0.67945 0.3048)
			(end -0.67945 -0.305054)
			(stroke
				(width 0.1)
				(type default)
			)
			(layer "F.Fab")
		)
		(fp_line
			(start -0.67945 -0.305054)
			(end -0.12065 -0.305054)
			(stroke
				(width 0.1)
				(type default)
			)
			(layer "F.Fab")
		)
		(pad "1" smd circle
			(at -0.40005 0 180)
			(size 0 0)
			(layers "F.Cu" "F.Mask" "F.Paste")
			(net "PVDD11_S3_P1")
		)
		(pad "2" smd circle
			(at 0.40005 0 180)
			(size 0 0)
			(layers "F.Cu" "F.Mask" "F.Paste")
			(net "VSENSE_PVDD11_S3_P1_DP")
		)
	)
)
